# BASEBOARD_FAB2 (Tioga Pass) — schematic netlist excerpt (pin names and nets, part order shuffled) for the footprints in the layout excerpt that follows; sources: Cadence DE-HDL packaged netlist, KiCad conversion of Wiwynn_Tioga_Pass_MB.brd

C1M33  CAP_A  0.1UF 16V 10% X7R  pkg 0402V  page 113 : A = JTAG_MCP_TMS_R1 ; B = GND
R9B6  RES  1.00K 1% CHIP  pkg 0402  page 167 : A = P3V3_STBY ; B = PU_TMP421_1_A1
R8D16  RES  10.0K 1% CHIP  pkg 0402  page 125 : A = P3V3_STBY ; B = RMII_PCH_SPRNGVLLE_ARB_OUT

(kicad_pcb
	(version 20260206)
	(generator "pcbnew")
	(generator_version "10.0")
	(general
		(thickness 1.6)
		(legacy_teardrops no)
	)
	(paper "A4")
	(title_block
		(title "Wiwynn_Tioga_Pass_MB.brd")
		(comment 1 "Tioga Pass / footprints 3896-3898 of 4770")
	)
	(layers
		(0 "F.Cu" signal "TOP")
		(4 "In1.Cu" signal "L2GND")
		(6 "In2.Cu" signal "L3")
		(8 "In3.Cu" signal "L4GND")
		(10 "In4.Cu" signal "L5")
		(12 "In5.Cu" signal "L6GND")
		(14 "In6.Cu" signal "L7VCC")
		(16 "In7.Cu" signal "L8VCC")
		(18 "In8.Cu" signal "L9GND")
		(20 "In9.Cu" signal "L10")
		(22 "In10.Cu" signal "L11GND")
		(24 "In11.Cu" signal "L12")
		(26 "In12.Cu" signal "L13GND")
		(2 "B.Cu" signal "BOTTOM")
		(9 "F.Adhes" user "F.Adhesive")
		(11 "B.Adhes" user "B.Adhesive")
		(13 "F.Paste" user "Package Geometry/Pastemask Top")
		(15 "B.Paste" user "Package Geometry/Pastemask Bottom")
		(5 "F.SilkS" user "Ref Des/Silkscreen Top")
		(7 "B.SilkS" user "Ref Des/Silkscreen Bottom")
		(1 "F.Mask" user "Board Geometry/Soldermask Top")
		(3 "B.Mask" user "Board Geometry/Soldermask Bottom")
		(17 "Dwgs.User" user "User.Drawings")
		(19 "Cmts.User" user "User.Comments")
		(21 "Eco1.User" user "User.Eco1")
		(23 "Eco2.User" user "User.Eco2")
		(25 "Edge.Cuts" user "Board Geometry/Outline")
		(27 "Margin" user)
		(31 "F.CrtYd" user "Package Geometry/Place Bound Top")
		(29 "B.CrtYd" user "Package Geometry/Place Bound Bottom")
		(35 "F.Fab" user "Ref Des/Assembly Top")
		(33 "B.Fab" user "Ref Des/Assembly Bottom")
	)
	(footprint ""
		(layer "B.Cu")
		(at 451.9422 -129.9464)
		(property "Reference" "C1M33"
			(at 0 0 0)
			(layer "B.SilkS")
			(hide yes)
			(effects
				(font
					(size 1.27 1.27)
				)
				(justify mirror)
			)
		)
		(property "Value" ""
			(at 0 0 0)
			(layer "B.Fab")
			(effects
				(font
					(size 1.27 1.27)
				)
				(justify mirror)
			)
		)
		(duplicate_pad_numbers_are_jumpers no)
		(fp_poly
			(pts
				(xy -0.3048 -0.1016) (xy -0.3048 0.9906) (xy 0.3048 0.9906) (xy 0.3048 -0.1016)
			)
			(stroke
				(width 0)
				(type default)
			)
			(fill no)
			(layer "B.CrtYd")
		)
		(fp_line
			(start -0.3048 -0.1016)
			(end 0.3048 -0.1016)
			(stroke
				(width 0.1)
				(type default)
			)
			(layer "B.Fab")
		)
		(fp_line
			(start -0.3048 0.9906)
			(end -0.3048 -0.1016)
			(stroke
				(width 0.1)
				(type default)
			)
			(layer "B.Fab")
		)
		(fp_line
			(start 0.3048 -0.1016)
			(end 0.3048 0.9906)
			(stroke
				(width 0.1)
				(type default)
			)
			(layer "B.Fab")
		)
		(fp_line
			(start 0.3048 0.9906)
			(end -0.3048 0.9906)
			(stroke
				(width 0.1)
				(type default)
			)
			(layer "B.Fab")
		)
		(pad "1" smd rect
			(at 0 0 180)
			(size 0.508 0.508)
			(layers "B.Cu" "B.Mask" "B.Paste")
			(net "JTAG_MCP_TMS_R1")
		)
		(pad "2" smd rect
			(at 0 0.889 180)
			(size 0.508 0.508)
			(layers "B.Cu" "B.Mask" "B.Paste")
			(net "GND")
		)
		(zone
			(layer "B.Cu")
			(hatch none 0.5)
			(connect_pads
				(clearance 0)
			)
			(min_thickness 0.25)
			(keepout
				(tracks allowed)
				(vias not_allowed)
				(pads allowed)
				(copperpour not_allowed)
				(footprints allowed)
			)
			(placement
				(enabled no)
				(sheetname "")
			)
			(fill
				(thermal_gap 0.5)
				(thermal_bridge_width 0.5)
				(island_removal_mode 0)
			)
			(polygon
				(pts
					(xy 452.1962 -129.6924) (xy 451.6882 -129.6924) (xy 451.6882 -129.3114) (xy 452.1962 -129.3114)
				)
			)
		)
		(zone
			(layer "B.Cu")
			(hatch none 0.5)
			(connect_pads
				(clearance 0)
			)
			(min_thickness 0.25)
			(keepout
				(tracks not_allowed)
				(vias allowed)
				(pads allowed)
				(copperpour not_allowed)
				(footprints allowed)
			)
			(placement
				(enabled no)
				(sheetname "")
			)
			(fill
				(thermal_gap 0.5)
				(thermal_bridge_width 0.5)
				(island_removal_mode 0)
			)
			(polygon
				(pts
					(xy 452.1962 -129.3114) (xy 451.6882 -129.3114) (xy 451.6882 -129.6924) (xy 452.1962 -129.6924)
				)
			)
		)
	)
	(footprint ""
		(layer "B.Cu")
		(at 491.07344 -123.56592 -90)
		(property "Reference" "R9B6"
			(at 0 0 90)
			(layer "B.SilkS")
			(hide yes)
			(effects
				(font
					(size 1.27 1.27)
				)
				(justify mirror)
			)
		)
		(property "Value" ""
			(at 0 0 90)
			(layer "B.Fab")
			(effects
				(font
					(size 1.27 1.27)
				)
				(justify mirror)
			)
		)
		(duplicate_pad_numbers_are_jumpers no)
		(fp_rect
			(start 0.2794 -0.1016)
			(end -0.2794 0.9906)
			(stroke
				(width 0)
				(type default)
			)
			(fill no)
			(layer "B.CrtYd")
		)
		(fp_line
			(start -0.2794 0.9906)
			(end -0.2794 -0.1016)
			(stroke
				(width 0.1)
				(type default)
			)
			(layer "B.Fab")
		)
		(fp_line
			(start 0.2794 0.9906)
			(end -0.2794 0.9906)
			(stroke
				(width 0.1)
				(type default)
			)
			(layer "B.Fab")
		)
		(fp_line
			(start -0.2794 -0.1016)
			(end 0.2794 -0.1016)
			(stroke
				(width 0.1)
				(type default)
			)
			(layer "B.Fab")
		)
		(fp_line
			(start 0.2794 -0.1016)
			(end 0.2794 0.9906)
			(stroke
				(width 0.1)
				(type default)
			)
			(layer "B.Fab")
		)
		(pad "1" smd rect
			(at 0 0 90)
			(size 0.508 0.508)
			(layers "B.Cu" "B.Mask" "B.Paste")
			(net "P3V3_STBY")
		)
		(pad "2" smd rect
			(at 0 0.889 90)
			(size 0.508 0.508)
			(layers "B.Cu" "B.Mask" "B.Paste")
			(net "PU_TMP421_1_A1")
		)
		(zone
			(layer "B.Cu")
			(hatch none 0.5)
			(connect_pads
				(clearance 0)
			)
			(min_thickness 0.25)
			(keepout
				(tracks not_allowed)
				(vias allowed)
				(pads allowed)
				(copperpour not_allowed)
				(footprints allowed)
			)
			(placement
				(enabled no)
				(sheetname "")
			)
			(fill
				(thermal_gap 0.5)
				(thermal_bridge_width 0.5)
				(island_removal_mode 0)
			)
			(polygon
				(pts
					(xy 490.81944 -123.31192) (xy 490.81944 -123.81992) (xy 490.43844 -123.81992) (xy 490.43844 -123.31192)
				)
			)
		)
		(zone
			(layer "B.Cu")
			(hatch none 0.5)
			(connect_pads
				(clearance 0)
			)
			(min_thickness 0.25)
			(keepout
				(tracks allowed)
				(vias not_allowed)
				(pads allowed)
				(copperpour not_allowed)
				(footprints allowed)
			)
			(placement
				(enabled no)
				(sheetname "")
			)
			(fill
				(thermal_gap 0.5)
				(thermal_bridge_width 0.5)
				(island_removal_mode 0)
			)
			(polygon
				(pts
					(xy 490.81944 -123.31192) (xy 490.81944 -123.81992) (xy 490.43844 -123.81992) (xy 490.43844 -123.31192)
				)
			)
		)
	)
	(footprint ""
		(layer "B.Cu")
		(at 387.75894 -85.51672 90)
		(property "Reference" "R8D16"
			(at 0.8382 -0.67818 90)
			(unlocked yes)
			(layer "B.SilkS")
			(effects
				(font
					(size 0.4064 0.254)
					(thickness 0.1524)
				)
				(justify left mirror)
			)
		)
		(property "Value" ""
			(at 0 0 90)
			(layer "B.Fab")
			(effects
				(font
					(size 1.27 1.27)
				)
				(justify mirror)
			)
		)
		(duplicate_pad_numbers_are_jumpers no)
		(fp_poly
			(pts
				(xy 0.2794 -0.1016) (xy -0.2794 -0.1016) (xy -0.2794 0.9906) (xy 0.2794 0.9906)
			)
			(stroke
				(width 0)
				(type default)
			)
			(fill no)
			(layer "B.CrtYd")
		)
		(fp_line
			(start 0.2794 -0.1016)
			(end 0.2794 0.9906)
			(stroke
				(width 0.1)
				(type default)
			)
			(layer "B.Fab")
		)
		(fp_line
			(start -0.2794 -0.1016)
			(end 0.2794 -0.1016)
			(stroke
				(width 0.1)
				(type default)
			)
			(layer "B.Fab")
		)
		(fp_line
			(start 0.2794 0.9906)
			(end -0.2794 0.9906)
			(stroke
				(width 0.1)
				(type default)
			)
			(layer "B.Fab")
		)
		(fp_line
			(start -0.2794 0.9906)
			(end -0.2794 -0.1016)
			(stroke
				(width 0.1)
				(type default)
			)
			(layer "B.Fab")
		)
		(pad "1" smd rect
			(at 0 0 270)
			(size 0.508 0.508)
			(layers "B.Cu" "B.Mask" "B.Paste")
			(net "P3V3_STBY")
		)
		(pad "2" smd rect
			(at 0 0.889 270)
			(size 0.508 0.508)
			(layers "B.Cu" "B.Mask" "B.Paste")
			(net "RMII_PCH_SPRNGVLLE_ARB_OUT")
		)
		(zone
			(layer "B.Cu")
			(hatch none 0.5)
			(connect_pads
				(clearance 0)
			)
			(min_thickness 0.25)
			(keepout
				(tracks allowed)
				(vias not_allowed)
				(pads allowed)
				(copperpour not_allowed)
				(footprints allowed)
			)
			(placement
				(enabled no)
				(sheetname "")
			)
			(fill
				(thermal_gap 0.5)
				(thermal_bridge_width 0.5)
				(island_removal_mode 0)
			)
			(polygon
				(pts
					(xy 388.01294 -85.77072) (xy 388.01294 -85.26272) (xy 388.39394 -85.26272) (xy 388.39394 -85.77072)
				)
			)
		)
		(zone
			(layer "B.Cu")
			(hatch none 0.5)
			(connect_pads
				(clearance 0)
			)
			(min_thickness 0.25)
			(keepout
				(tracks not_allowed)
				(vias allowed)
				(pads allowed)
				(copperpour not_allowed)
				(footprints allowed)
			)
			(placement
				(enabled no)
				(sheetname "")
			)
			(fill
				(thermal_gap 0.5)
				(thermal_bridge_width 0.5)
				(island_removal_mode 0)
			)
			(polygon
				(pts
					(xy 388.39394 -85.77072) (xy 388.39394 -85.26272) (xy 388.01294 -85.26272) (xy 388.01294 -85.77072)
				)
			)
		)
	)
)
